# S9S_MB_2U (Grand Teton) — schematic netlist excerpt (pin names and nets, part order shuffled) for the footprints in the layout excerpt that follows; sources: Cadence DE-HDL packaged netlist, KiCad conversion of 03242023_DA0F0TMBIJ0_F0T_Motherboard_J_brd_V01_OCP.brd

C2031  Q_CAP  1UF 25V 10% X6S  pkg C0402  page 152 : A = P3V3_AUX_USB_HUB ; B = GND
PR107  Q_RES  0 5% EMPTY  pkg 0402LF  page 274 : A = P12V_AUX ; B = PVCCINFAON_CPU0_CSPIN

(kicad_pcb
	(version 20260206)
	(generator "pcbnew")
	(generator_version "10.0")
	(general
		(thickness 1.6)
		(legacy_teardrops no)
	)
	(paper "A4")
	(title_block
		(title "03242023_DA0F0TMBIJ0_F0T_Motherboard_J_brd_V01_OCP.brd")
		(comment 1 "Grand Teton / footprints 5222-5223 of 6105")
	)
	(layers
		(0 "F.Cu" signal "TOP")
		(4 "In1.Cu" signal "GND")
		(6 "In2.Cu" signal "IN1")
		(8 "In3.Cu" signal "GND1")
		(10 "In4.Cu" signal "IN2")
		(12 "In5.Cu" signal "GND2")
		(14 "In6.Cu" signal "IN3")
		(16 "In7.Cu" signal "GND3")
		(18 "In8.Cu" signal "VCC")
		(20 "In9.Cu" signal "VCC1")
		(22 "In10.Cu" signal "GND4")
		(24 "In11.Cu" signal "IN4")
		(26 "In12.Cu" signal "GND5")
		(28 "In13.Cu" signal "IN5")
		(30 "In14.Cu" signal "GND6")
		(32 "In15.Cu" signal "IN6")
		(34 "In16.Cu" signal "GND7")
		(2 "B.Cu" signal "BOTTOM")
		(9 "F.Adhes" user "F.Adhesive")
		(11 "B.Adhes" user "B.Adhesive")
		(13 "F.Paste" user "Package Geometry/Pastemask Top")
		(15 "B.Paste" user "Package Geometry/Pastemask Bottom")
		(5 "F.SilkS" user "Ref Des/Silkscreen Top")
		(7 "B.SilkS" user "Ref Des/Silkscreen Bottom")
		(1 "F.Mask" user "Board Geometry/Soldermask Top")
		(3 "B.Mask" user "Board Geometry/Soldermask Bottom")
		(17 "Dwgs.User" user "User.Drawings")
		(19 "Cmts.User" user "User.Comments")
		(21 "Eco1.User" user "User.Eco1")
		(23 "Eco2.User" user "User.Eco2")
		(25 "Edge.Cuts" user "Board Geometry/Outline")
		(27 "Margin" user)
		(31 "F.CrtYd" user "Package Geometry/Place Bound Top")
		(29 "B.CrtYd" user "Package Geometry/Place Bound Bottom")
		(35 "F.Fab" user "Ref Des/Assembly Top")
		(33 "B.Fab" user "Ref Des/Assembly Bottom")
	)
	(footprint ""
		(layer "B.Cu")
		(at 14.616176 -101.217984 90)
		(property "Reference" "C2031"
			(at 0 0 90)
			(layer "B.SilkS")
			(hide yes)
			(effects
				(font
					(size 1.27 1.27)
				)
				(justify mirror)
			)
		)
		(property "Value" ""
			(at 0 0 90)
			(layer "B.Fab")
			(effects
				(font
					(size 1.27 1.27)
				)
				(justify mirror)
			)
		)
		(duplicate_pad_numbers_are_jumpers no)
		(fp_line
			(start 0.7874 -0.4064)
			(end -0.7874 -0.4064)
			(stroke
				(width 0.1524)
				(type default)
			)
			(layer "B.SilkS")
		)
		(fp_line
			(start -0.7874 -0.4064)
			(end -0.7874 0.4064)
			(stroke
				(width 0.1524)
				(type default)
			)
			(layer "B.SilkS")
		)
		(fp_line
			(start 0.7874 0.4064)
			(end 0.7874 -0.4064)
			(stroke
				(width 0.1524)
				(type default)
			)
			(layer "B.SilkS")
		)
		(fp_line
			(start -0.7874 0.4064)
			(end 0.7874 0.4064)
			(stroke
				(width 0.1524)
				(type default)
			)
			(layer "B.SilkS")
		)
		(fp_line
			(start 0.67945 -0.305054)
			(end 0.12065 -0.305054)
			(stroke
				(width 0.1)
				(type default)
			)
			(layer "B.Fab")
		)
		(fp_line
			(start 0.12065 -0.305054)
			(end 0.12065 -0.2794)
			(stroke
				(width 0.1)
				(type default)
			)
			(layer "B.Fab")
		)
		(fp_line
			(start -0.12065 -0.3048)
			(end -0.67945 -0.3048)
			(stroke
				(width 0.1)
				(type default)
			)
			(layer "B.Fab")
		)
		(fp_line
			(start -0.67945 -0.3048)
			(end -0.67945 0.3048)
			(stroke
				(width 0.1)
				(type default)
			)
			(layer "B.Fab")
		)
		(fp_line
			(start 0.12065 -0.2794)
			(end -0.12065 -0.2794)
			(stroke
				(width 0.1)
				(type default)
			)
			(layer "B.Fab")
		)
		(fp_line
			(start -0.12065 -0.2794)
			(end -0.12065 -0.3048)
			(stroke
				(width 0.1)
				(type default)
			)
			(layer "B.Fab")
		)
		(fp_line
			(start 0.12065 0.2794)
			(end 0.12065 0.3048)
			(stroke
				(width 0.1)
				(type default)
			)
			(layer "B.Fab")
		)
		(fp_line
			(start -0.120396 0.2794)
			(end 0.12065 0.2794)
			(stroke
				(width 0.1)
				(type default)
			)
			(layer "B.Fab")
		)
		(fp_line
			(start 0.67945 0.3048)
			(end 0.67945 -0.305054)
			(stroke
				(width 0.1)
				(type default)
			)
			(layer "B.Fab")
		)
		(fp_line
			(start 0.12065 0.3048)
			(end 0.67945 0.3048)
			(stroke
				(width 0.1)
				(type default)
			)
			(layer "B.Fab")
		)
		(fp_line
			(start -0.120396 0.3048)
			(end -0.120396 0.2794)
			(stroke
				(width 0.1)
				(type default)
			)
			(layer "B.Fab")
		)
		(fp_line
			(start -0.67945 0.3048)
			(end -0.120396 0.3048)
			(stroke
				(width 0.1)
				(type default)
			)
			(layer "B.Fab")
		)
		(pad "1" smd circle
			(at 0.40005 0 270)
			(size 0 0)
			(layers "B.Cu" "B.Mask" "B.Paste")
			(net "P3V3_AUX_USB_HUB")
		)
		(pad "2" smd circle
			(at -0.40005 0 270)
			(size 0 0)
			(layers "B.Cu" "B.Mask" "B.Paste")
			(net "GND")
		)
	)
	(footprint ""
		(layer "B.Cu")
		(at 420.682166 -136.162034 180)
		(property "Reference" "PR107"
			(at 0 0 0)
			(layer "B.SilkS")
			(hide yes)
			(effects
				(font
					(size 1.27 1.27)
				)
				(justify mirror)
			)
		)
		(property "Value" ""
			(at 0 0 0)
			(layer "B.Fab")
			(effects
				(font
					(size 1.27 1.27)
				)
				(justify mirror)
			)
		)
		(duplicate_pad_numbers_are_jumpers no)
		(fp_line
			(start 0.7874 0.4064)
			(end 0.7874 -0.4064)
			(stroke
				(width 0.1524)
				(type default)
			)
			(layer "B.SilkS")
		)
		(fp_line
			(start 0.7874 -0.4064)
			(end -0.7874 -0.4064)
			(stroke
				(width 0.1524)
				(type default)
			)
			(layer "B.SilkS")
		)
		(fp_line
			(start -0.7874 0.4064)
			(end 0.7874 0.4064)
			(stroke
				(width 0.1524)
				(type default)
			)
			(layer "B.SilkS")
		)
		(fp_line
			(start -0.7874 -0.4064)
			(end -0.7874 0.4064)
			(stroke
				(width 0.1524)
				(type default)
			)
			(layer "B.SilkS")
		)
		(fp_line
			(start 0.67945 0.3048)
			(end 0.67945 -0.305054)
			(stroke
				(width 0.1)
				(type default)
			)
			(layer "B.Fab")
		)
		(fp_line
			(start 0.67945 -0.305054)
			(end 0.12065 -0.305054)
			(stroke
				(width 0.1)
				(type default)
			)
			(layer "B.Fab")
		)
		(fp_line
			(start 0.12065 0.3048)
			(end 0.67945 0.3048)
			(stroke
				(width 0.1)
				(type default)
			)
			(layer "B.Fab")
		)
		(fp_line
			(start 0.12065 0.2794)
			(end 0.12065 0.3048)
			(stroke
				(width 0.1)
				(type default)
			)
			(layer "B.Fab")
		)
		(fp_line
			(start 0.12065 -0.2794)
			(end -0.12065 -0.2794)
			(stroke
				(width 0.1)
				(type default)
			)
			(layer "B.Fab")
		)
		(fp_line
			(start 0.12065 -0.305054)
			(end 0.12065 -0.2794)
			(stroke
				(width 0.1)
				(type default)
			)
			(layer "B.Fab")
		)
		(fp_line
			(start -0.120396 0.3048)
			(end -0.120396 0.2794)
			(stroke
				(width 0.1)
				(type default)
			)
			(layer "B.Fab")
		)
		(fp_line
			(start -0.120396 0.2794)
			(end 0.12065 0.2794)
			(stroke
				(width 0.1)
				(type default)
			)
			(layer "B.Fab")
		)
		(fp_line
			(start -0.12065 -0.2794)
			(end -0.12065 -0.3048)
			(stroke
				(width 0.1)
				(type default)
			)
			(layer "B.Fab")
		)
		(fp_line
			(start -0.12065 -0.3048)
			(end -0.67945 -0.3048)
			(stroke
				(width 0.1)
				(type default)
			)
			(layer "B.Fab")
		)
		(fp_line
			(start -0.67945 0.3048)
			(end -0.120396 0.3048)
			(stroke
				(width 0.1)
				(type default)
			)
			(layer "B.Fab")
		)
		(fp_line
			(start -0.67945 -0.3048)
			(end -0.67945 0.3048)
			(stroke
				(width 0.1)
				(type default)
			)
			(layer "B.Fab")
		)
		(pad "1" smd circle
			(at 0.40005 0)
			(size 0 0)
			(layers "B.Cu" "B.Mask" "B.Paste")
			(net "P12V_AUX")
		)
		(pad "2" smd circle
			(at -0.40005 0)
			(size 0 0)
			(layers "B.Cu" "B.Mask" "B.Paste")
			(net "PVCCINFAON_CPU0_CSPIN")
		)
	)
)
